# S9S_MB_2U (Grand Teton) — schematic netlist excerpt (pin names and nets, part order shuffled) for the footprints in the layout excerpt that follows; sources: Cadence DE-HDL packaged netlist, KiCad conversion of 03242023_DA0F0TMBIJ0_F0T_Motherboard_J_brd_V01_OCP.brd

PR520  Q_RES  100 1% CHIP  pkg 0402LF  page 274 : A = VSENSE_PVCCFA_EHV_CPU0_DN ; B = GND
C229  Q_CAP  10UF 6.3V 20% X6S  pkg C0402  page 77 : A = PVCCIN_CPU1 ; B = GND

(kicad_pcb
	(version 20260206)
	(generator "pcbnew")
	(generator_version "10.0")
	(general
		(thickness 1.6)
		(legacy_teardrops no)
	)
	(paper "A4")
	(title_block
		(title "03242023_DA0F0TMBIJ0_F0T_Motherboard_J_brd_V01_OCP.brd")
		(comment 1 "Grand Teton / footprints 2905-2906 of 6105")
	)
	(layers
		(0 "F.Cu" signal "TOP")
		(4 "In1.Cu" signal "GND")
		(6 "In2.Cu" signal "IN1")
		(8 "In3.Cu" signal "GND1")
		(10 "In4.Cu" signal "IN2")
		(12 "In5.Cu" signal "GND2")
		(14 "In6.Cu" signal "IN3")
		(16 "In7.Cu" signal "GND3")
		(18 "In8.Cu" signal "VCC")
		(20 "In9.Cu" signal "VCC1")
		(22 "In10.Cu" signal "GND4")
		(24 "In11.Cu" signal "IN4")
		(26 "In12.Cu" signal "GND5")
		(28 "In13.Cu" signal "IN5")
		(30 "In14.Cu" signal "GND6")
		(32 "In15.Cu" signal "IN6")
		(34 "In16.Cu" signal "GND7")
		(2 "B.Cu" signal "BOTTOM")
		(9 "F.Adhes" user "F.Adhesive")
		(11 "B.Adhes" user "B.Adhesive")
		(13 "F.Paste" user "Package Geometry/Pastemask Top")
		(15 "B.Paste" user "Package Geometry/Pastemask Bottom")
		(5 "F.SilkS" user "Ref Des/Silkscreen Top")
		(7 "B.SilkS" user "Ref Des/Silkscreen Bottom")
		(1 "F.Mask" user "Board Geometry/Soldermask Top")
		(3 "B.Mask" user "Board Geometry/Soldermask Bottom")
		(17 "Dwgs.User" user "User.Drawings")
		(19 "Cmts.User" user "User.Comments")
		(21 "Eco1.User" user "User.Eco1")
		(23 "Eco2.User" user "User.Eco2")
		(25 "Edge.Cuts" user "Board Geometry/Outline")
		(27 "Margin" user)
		(31 "F.CrtYd" user "Package Geometry/Place Bound Top")
		(29 "B.CrtYd" user "Package Geometry/Place Bound Bottom")
		(35 "F.Fab" user "Ref Des/Assembly Top")
		(33 "B.Fab" user "Ref Des/Assembly Bottom")
	)
	(footprint ""
		(layer "F.Cu")
		(at 397.254476 -148.010118 90)
		(property "Reference" "PR520"
			(at 0 0 90)
			(layer "F.SilkS")
			(hide yes)
			(effects
				(font
					(size 1.27 1.27)
				)
			)
		)
		(property "Value" ""
			(at 0 0 90)
			(layer "F.Fab")
			(effects
				(font
					(size 1.27 1.27)
				)
			)
		)
		(duplicate_pad_numbers_are_jumpers no)
		(fp_line
			(start 0.7874 -0.4064)
			(end 0.7874 0.4064)
			(stroke
				(width 0.1524)
				(type default)
			)
			(layer "F.SilkS")
		)
		(fp_line
			(start -0.7874 -0.4064)
			(end 0.7874 -0.4064)
			(stroke
				(width 0.1524)
				(type default)
			)
			(layer "F.SilkS")
		)
		(fp_line
			(start 0.7874 0.4064)
			(end -0.7874 0.4064)
			(stroke
				(width 0.1524)
				(type default)
			)
			(layer "F.SilkS")
		)
		(fp_line
			(start -0.7874 0.4064)
			(end -0.7874 -0.4064)
			(stroke
				(width 0.1524)
				(type default)
			)
			(layer "F.SilkS")
		)
		(fp_line
			(start -0.12065 -0.305054)
			(end -0.12065 -0.2794)
			(stroke
				(width 0.1)
				(type default)
			)
			(layer "F.Fab")
		)
		(fp_line
			(start -0.67945 -0.305054)
			(end -0.12065 -0.305054)
			(stroke
				(width 0.1)
				(type default)
			)
			(layer "F.Fab")
		)
		(fp_line
			(start 0.67945 -0.3048)
			(end 0.67945 0.3048)
			(stroke
				(width 0.1)
				(type default)
			)
			(layer "F.Fab")
		)
		(fp_line
			(start 0.12065 -0.3048)
			(end 0.67945 -0.3048)
			(stroke
				(width 0.1)
				(type default)
			)
			(layer "F.Fab")
		)
		(fp_line
			(start 0.12065 -0.2794)
			(end 0.12065 -0.3048)
			(stroke
				(width 0.1)
				(type default)
			)
			(layer "F.Fab")
		)
		(fp_line
			(start -0.12065 -0.2794)
			(end 0.12065 -0.2794)
			(stroke
				(width 0.1)
				(type default)
			)
			(layer "F.Fab")
		)
		(fp_line
			(start 0.120396 0.2794)
			(end -0.12065 0.2794)
			(stroke
				(width 0.1)
				(type default)
			)
			(layer "F.Fab")
		)
		(fp_line
			(start -0.12065 0.2794)
			(end -0.12065 0.3048)
			(stroke
				(width 0.1)
				(type default)
			)
			(layer "F.Fab")
		)
		(fp_line
			(start 0.67945 0.3048)
			(end 0.120396 0.3048)
			(stroke
				(width 0.1)
				(type default)
			)
			(layer "F.Fab")
		)
		(fp_line
			(start 0.120396 0.3048)
			(end 0.120396 0.2794)
			(stroke
				(width 0.1)
				(type default)
			)
			(layer "F.Fab")
		)
		(fp_line
			(start -0.12065 0.3048)
			(end -0.67945 0.3048)
			(stroke
				(width 0.1)
				(type default)
			)
			(layer "F.Fab")
		)
		(fp_line
			(start -0.67945 0.3048)
			(end -0.67945 -0.305054)
			(stroke
				(width 0.1)
				(type default)
			)
			(layer "F.Fab")
		)
		(pad "1" smd circle
			(at -0.40005 0 90)
			(size 0 0)
			(layers "F.Cu" "F.Mask" "F.Paste")
			(net "VSENSE_PVCCFA_EHV_CPU0_DN")
		)
		(pad "2" smd circle
			(at 0.40005 0 90)
			(size 0 0)
			(layers "F.Cu" "F.Mask" "F.Paste")
			(net "GND")
		)
	)
	(footprint ""
		(layer "F.Cu")
		(at 118.542816 -249.320558 -90)
		(property "Reference" "C229"
			(at 0 0 270)
			(layer "F.SilkS")
			(hide yes)
			(effects
				(font
					(size 1.27 1.27)
				)
			)
		)
		(property "Value" ""
			(at 0 0 270)
			(layer "F.Fab")
			(effects
				(font
					(size 1.27 1.27)
				)
			)
		)
		(duplicate_pad_numbers_are_jumpers no)
		(fp_line
			(start -0.7874 0.4064)
			(end -0.7874 -0.4064)
			(stroke
				(width 0.1524)
				(type default)
			)
			(layer "F.SilkS")
		)
		(fp_line
			(start 0.7874 0.4064)
			(end -0.7874 0.4064)
			(stroke
				(width 0.1524)
				(type default)
			)
			(layer "F.SilkS")
		)
		(fp_line
			(start -0.7874 -0.4064)
			(end 0.7874 -0.4064)
			(stroke
				(width 0.1524)
				(type default)
			)
			(layer "F.SilkS")
		)
		(fp_line
			(start 0.7874 -0.4064)
			(end 0.7874 0.4064)
			(stroke
				(width 0.1524)
				(type default)
			)
			(layer "F.SilkS")
		)
		(fp_line
			(start -0.67945 0.3048)
			(end -0.67945 -0.305054)
			(stroke
				(width 0.1)
				(type default)
			)
			(layer "F.Fab")
		)
		(fp_line
			(start -0.12065 0.3048)
			(end -0.67945 0.3048)
			(stroke
				(width 0.1)
				(type default)
			)
			(layer "F.Fab")
		)
		(fp_line
			(start 0.120396 0.3048)
			(end 0.120396 0.2794)
			(stroke
				(width 0.1)
				(type default)
			)
			(layer "F.Fab")
		)
		(fp_line
			(start 0.67945 0.3048)
			(end 0.120396 0.3048)
			(stroke
				(width 0.1)
				(type default)
			)
			(layer "F.Fab")
		)
		(fp_line
			(start -0.12065 0.2794)
			(end -0.12065 0.3048)
			(stroke
				(width 0.1)
				(type default)
			)
			(layer "F.Fab")
		)
		(fp_line
			(start 0.120396 0.2794)
			(end -0.12065 0.2794)
			(stroke
				(width 0.1)
				(type default)
			)
			(layer "F.Fab")
		)
		(fp_line
			(start -0.12065 -0.2794)
			(end 0.12065 -0.2794)
			(stroke
				(width 0.1)
				(type default)
			)
			(layer "F.Fab")
		)
		(fp_line
			(start 0.12065 -0.2794)
			(end 0.12065 -0.3048)
			(stroke
				(width 0.1)
				(type default)
			)
			(layer "F.Fab")
		)
		(fp_line
			(start 0.12065 -0.3048)
			(end 0.67945 -0.3048)
			(stroke
				(width 0.1)
				(type default)
			)
			(layer "F.Fab")
		)
		(fp_line
			(start 0.67945 -0.3048)
			(end 0.67945 0.3048)
			(stroke
				(width 0.1)
				(type default)
			)
			(layer "F.Fab")
		)
		(fp_line
			(start -0.67945 -0.305054)
			(end -0.12065 -0.305054)
			(stroke
				(width 0.1)
				(type default)
			)
			(layer "F.Fab")
		)
		(fp_line
			(start -0.12065 -0.305054)
			(end -0.12065 -0.2794)
			(stroke
				(width 0.1)
				(type default)
			)
			(layer "F.Fab")
		)
		(pad "1" smd circle
			(at -0.40005 0 270)
			(size 0 0)
			(layers "F.Cu" "F.Mask" "F.Paste")
			(net "PVCCIN_CPU1")
		)
		(pad "2" smd circle
			(at 0.40005 0 270)
			(size 0 0)
			(layers "F.Cu" "F.Mask" "F.Paste")
			(net "GND")
		)
	)
)
